(kicad_pcb
	(version 20260206)
	(generator "pcbnew")
	(generator_version "10.0")
	(general
		(thickness 1.6)
		(legacy_teardrops no)
	)
	(paper "A4")
	(title_block
		(title "04192023_DAF0TMB3IC0_F0TG_MB_C_brd_V02_OCP.brd")
		(comment 1 "Grand Teton / footprints 4710-4717 of 8354")
	)
	(layers
		(0 "F.Cu" signal "TOP")
		(4 "In1.Cu" signal "GND")
		(6 "In2.Cu" signal "IN1")
		(8 "In3.Cu" signal "GND1")
		(10 "In4.Cu" signal "IN2")
		(12 "In5.Cu" signal "GND2")
		(14 "In6.Cu" signal "IN3")
		(16 "In7.Cu" signal "GND3")
		(18 "In8.Cu" signal "VCC")
		(20 "In9.Cu" signal "VCC1")
		(22 "In10.Cu" signal "GND4")
		(24 "In11.Cu" signal "IN4")
		(26 "In12.Cu" signal "GND5")
		(28 "In13.Cu" signal "IN5")
		(30 "In14.Cu" signal "GND6")
		(32 "In15.Cu" signal "IN6")
		(34 "In16.Cu" signal "GND7")
		(2 "B.Cu" signal "BOTTOM")
		(9 "F.Adhes" user "F.Adhesive")
		(11 "B.Adhes" user "B.Adhesive")
		(13 "F.Paste" user "Package Geometry/Pastemask Top")
		(15 "B.Paste" user "Package Geometry/Pastemask Bottom")
		(5 "F.SilkS" user "Ref Des/Silkscreen Top")
		(7 "B.SilkS" user "Ref Des/Silkscreen Bottom")
		(1 "F.Mask" user "Board Geometry/Soldermask Top")
		(3 "B.Mask" user "Board Geometry/Soldermask Bottom")
		(17 "Dwgs.User" user "User.Drawings")
		(19 "Cmts.User" user "User.Comments")
		(21 "Eco1.User" user "User.Eco1")
		(23 "Eco2.User" user "User.Eco2")
		(25 "Edge.Cuts" user "Board Geometry/Outline")
		(27 "Margin" user)
		(31 "F.CrtYd" user "Package Geometry/Place Bound Top")
		(29 "B.CrtYd" user "Package Geometry/Place Bound Bottom")
		(35 "F.Fab" user "Ref Des/Assembly Top")
		(33 "B.Fab" user "Ref Des/Assembly Bottom")
	)
	(footprint ""
		(layer "F.Cu")
		(at 118.491 -423.672)
		(property "Reference" "R3392"
			(at 0 0 0)
			(layer "F.SilkS")
			(hide yes)
			(effects
				(font
					(size 1.27 1.27)
				)
			)
		)
		(property "Value" ""
			(at 0 0 0)
			(layer "F.Fab")
			(effects
				(font
					(size 1.27 1.27)
				)
			)
		)
		(duplicate_pad_numbers_are_jumpers no)
		(fp_line
			(start -0.7874 -0.4064)
			(end 0.7874 -0.4064)
			(stroke
				(width 0.1524)
				(type default)
			)
			(layer "F.SilkS")
		)
		(fp_line
			(start -0.7874 0.4064)
			(end -0.7874 -0.4064)
			(stroke
				(width 0.1524)
				(type default)
			)
			(layer "F.SilkS")
		)
		(fp_line
			(start 0.7874 -0.4064)
			(end 0.7874 0.4064)
			(stroke
				(width 0.1524)
				(type default)
			)
			(layer "F.SilkS")
		)
		(fp_line
			(start 0.7874 0.4064)
			(end -0.7874 0.4064)
			(stroke
				(width 0.1524)
				(type default)
			)
			(layer "F.SilkS")
		)
		(fp_line
			(start -0.67945 -0.305054)
			(end -0.12065 -0.305054)
			(stroke
				(width 0.1)
				(type default)
			)
			(layer "F.Fab")
		)
		(fp_line
			(start -0.67945 0.3048)
			(end -0.67945 -0.305054)
			(stroke
				(width 0.1)
				(type default)
			)
			(layer "F.Fab")
		)
		(fp_line
			(start -0.12065 -0.305054)
			(end -0.12065 -0.2794)
			(stroke
				(width 0.1)
				(type default)
			)
			(layer "F.Fab")
		)
		(fp_line
			(start -0.12065 -0.2794)
			(end 0.12065 -0.2794)
			(stroke
				(width 0.1)
				(type default)
			)
			(layer "F.Fab")
		)
		(fp_line
			(start -0.12065 0.2794)
			(end -0.12065 0.3048)
			(stroke
				(width 0.1)
				(type default)
			)
			(layer "F.Fab")
		)
		(fp_line
			(start -0.12065 0.3048)
			(end -0.67945 0.3048)
			(stroke
				(width 0.1)
				(type default)
			)
			(layer "F.Fab")
		)
		(fp_line
			(start 0.120396 0.2794)
			(end -0.12065 0.2794)
			(stroke
				(width 0.1)
				(type default)
			)
			(layer "F.Fab")
		)
		(fp_line
			(start 0.120396 0.3048)
			(end 0.120396 0.2794)
			(stroke
				(width 0.1)
				(type default)
			)
			(layer "F.Fab")
		)
		(fp_line
			(start 0.12065 -0.3048)
			(end 0.67945 -0.3048)
			(stroke
				(width 0.1)
				(type default)
			)
			(layer "F.Fab")
		)
		(fp_line
			(start 0.12065 -0.2794)
			(end 0.12065 -0.3048)
			(stroke
				(width 0.1)
				(type default)
			)
			(layer "F.Fab")
		)
		(fp_line
			(start 0.67945 -0.3048)
			(end 0.67945 0.3048)
			(stroke
				(width 0.1)
				(type default)
			)
			(layer "F.Fab")
		)
		(fp_line
			(start 0.67945 0.3048)
			(end 0.120396 0.3048)
			(stroke
				(width 0.1)
				(type default)
			)
			(layer "F.Fab")
		)
		(pad "1" smd circle
			(at -0.40005 0)
			(size 0 0)
			(layers "F.Cu" "F.Mask" "F.Paste")
			(net "GPU_BASE_STBY_EN_BUF_R")
		)
		(pad "2" smd circle
			(at 0.40005 0)
			(size 0 0)
			(layers "F.Cu" "F.Mask" "F.Paste")
			(net "GPU_BASE_STBY_EN_BUF")
		)
	)
	(footprint ""
		(layer "F.Cu")
		(at 271.744948 -344.982038 90)
		(property "Reference" "PR291"
			(at 0 0 90)
			(layer "F.SilkS")
			(hide yes)
			(effects
				(font
					(size 1.27 1.27)
				)
			)
		)
		(property "Value" ""
			(at 0 0 90)
			(layer "F.Fab")
			(effects
				(font
					(size 1.27 1.27)
				)
			)
		)
		(duplicate_pad_numbers_are_jumpers no)
		(fp_line
			(start 0.7874 -0.4064)
			(end 0.7874 0.4064)
			(stroke
				(width 0.1524)
				(type default)
			)
			(layer "F.SilkS")
		)
		(fp_line
			(start -0.7874 -0.4064)
			(end 0.7874 -0.4064)
			(stroke
				(width 0.1524)
				(type default)
			)
			(layer "F.SilkS")
		)
		(fp_line
			(start 0.7874 0.4064)
			(end -0.7874 0.4064)
			(stroke
				(width 0.1524)
				(type default)
			)
			(layer "F.SilkS")
		)
		(fp_line
			(start -0.7874 0.4064)
			(end -0.7874 -0.4064)
			(stroke
				(width 0.1524)
				(type default)
			)
			(layer "F.SilkS")
		)
		(fp_line
			(start -0.12065 -0.305054)
			(end -0.12065 -0.2794)
			(stroke
				(width 0.1)
				(type default)
			)
			(layer "F.Fab")
		)
		(fp_line
			(start -0.67945 -0.305054)
			(end -0.12065 -0.305054)
			(stroke
				(width 0.1)
				(type default)
			)
			(layer "F.Fab")
		)
		(fp_line
			(start 0.67945 -0.3048)
			(end 0.67945 0.3048)
			(stroke
				(width 0.1)
				(type default)
			)
			(layer "F.Fab")
		)
		(fp_line
			(start 0.12065 -0.3048)
			(end 0.67945 -0.3048)
			(stroke
				(width 0.1)
				(type default)
			)
			(layer "F.Fab")
		)
		(fp_line
			(start 0.12065 -0.2794)
			(end 0.12065 -0.3048)
			(stroke
				(width 0.1)
				(type default)
			)
			(layer "F.Fab")
		)
		(fp_line
			(start -0.12065 -0.2794)
			(end 0.12065 -0.2794)
			(stroke
				(width 0.1)
				(type default)
			)
			(layer "F.Fab")
		)
		(fp_line
			(start 0.120396 0.2794)
			(end -0.12065 0.2794)
			(stroke
				(width 0.1)
				(type default)
			)
			(layer "F.Fab")
		)
		(fp_line
			(start -0.12065 0.2794)
			(end -0.12065 0.3048)
			(stroke
				(width 0.1)
				(type default)
			)
			(layer "F.Fab")
		)
		(fp_line
			(start 0.67945 0.3048)
			(end 0.120396 0.3048)
			(stroke
				(width 0.1)
				(type default)
			)
			(layer "F.Fab")
		)
		(fp_line
			(start 0.120396 0.3048)
			(end 0.120396 0.2794)
			(stroke
				(width 0.1)
				(type default)
			)
			(layer "F.Fab")
		)
		(fp_line
			(start -0.12065 0.3048)
			(end -0.67945 0.3048)
			(stroke
				(width 0.1)
				(type default)
			)
			(layer "F.Fab")
		)
		(fp_line
			(start -0.67945 0.3048)
			(end -0.67945 -0.305054)
			(stroke
				(width 0.1)
				(type default)
			)
			(layer "F.Fab")
		)
		(pad "1" smd circle
			(at -0.40005 0 90)
			(size 0 0)
			(layers "F.Cu" "F.Mask" "F.Paste")
			(net "SW_PVDDIO_P0_SW4_RC")
		)
		(pad "2" smd circle
			(at 0.40005 0 90)
			(size 0 0)
			(layers "F.Cu" "F.Mask" "F.Paste")
			(net "GND")
		)
	)
	(footprint ""
		(layer "F.Cu")
		(at 152.849834 -321.715892)
		(property "Reference" "C5024"
			(at 0 0 0)
			(layer "F.SilkS")
			(hide yes)
			(effects
				(font
					(size 1.27 1.27)
				)
			)
		)
		(property "Value" ""
			(at 0 0 0)
			(layer "F.Fab")
			(effects
				(font
					(size 1.27 1.27)
				)
			)
		)
		(duplicate_pad_numbers_are_jumpers no)
		(fp_line
			(start -0.7874 -0.4064)
			(end 0.7874 -0.4064)
			(stroke
				(width 0.1524)
				(type default)
			)
			(layer "F.SilkS")
		)
		(fp_line
			(start -0.7874 0.4064)
			(end -0.7874 -0.4064)
			(stroke
				(width 0.1524)
				(type default)
			)
			(layer "F.SilkS")
		)
		(fp_line
			(start 0.7874 -0.4064)
			(end 0.7874 0.4064)
			(stroke
				(width 0.1524)
				(type default)
			)
			(layer "F.SilkS")
		)
		(fp_line
			(start 0.7874 0.4064)
			(end -0.7874 0.4064)
			(stroke
				(width 0.1524)
				(type default)
			)
			(layer "F.SilkS")
		)
		(fp_line
			(start -0.67945 -0.305054)
			(end -0.12065 -0.305054)
			(stroke
				(width 0.1)
				(type default)
			)
			(layer "F.Fab")
		)
		(fp_line
			(start -0.67945 0.3048)
			(end -0.67945 -0.305054)
			(stroke
				(width 0.1)
				(type default)
			)
			(layer "F.Fab")
		)
		(fp_line
			(start -0.12065 -0.305054)
			(end -0.12065 -0.2794)
			(stroke
				(width 0.1)
				(type default)
			)
			(layer "F.Fab")
		)
		(fp_line
			(start -0.12065 -0.2794)
			(end 0.12065 -0.2794)
			(stroke
				(width 0.1)
				(type default)
			)
			(layer "F.Fab")
		)
		(fp_line
			(start -0.12065 0.2794)
			(end -0.12065 0.3048)
			(stroke
				(width 0.1)
				(type default)
			)
			(layer "F.Fab")
		)
		(fp_line
			(start -0.12065 0.3048)
			(end -0.67945 0.3048)
			(stroke
				(width 0.1)
				(type default)
			)
			(layer "F.Fab")
		)
		(fp_line
			(start 0.120396 0.2794)
			(end -0.12065 0.2794)
			(stroke
				(width 0.1)
				(type default)
			)
			(layer "F.Fab")
		)
		(fp_line
			(start 0.120396 0.3048)
			(end 0.120396 0.2794)
			(stroke
				(width 0.1)
				(type default)
			)
			(layer "F.Fab")
		)
		(fp_line
			(start 0.12065 -0.3048)
			(end 0.67945 -0.3048)
			(stroke
				(width 0.1)
				(type default)
			)
			(layer "F.Fab")
		)
		(fp_line
			(start 0.12065 -0.2794)
			(end 0.12065 -0.3048)
			(stroke
				(width 0.1)
				(type default)
			)
			(layer "F.Fab")
		)
		(fp_line
			(start 0.67945 -0.3048)
			(end 0.67945 0.3048)
			(stroke
				(width 0.1)
				(type default)
			)
			(layer "F.Fab")
		)
		(fp_line
			(start 0.67945 0.3048)
			(end 0.120396 0.3048)
			(stroke
				(width 0.1)
				(type default)
			)
			(layer "F.Fab")
		)
		(pad "1" smd circle
			(at -0.40005 0)
			(size 0 0)
			(layers "F.Cu" "F.Mask" "F.Paste")
			(net "RST_CPU1_RSMRST_N")
		)
		(pad "2" smd circle
			(at 0.40005 0)
			(size 0 0)
			(layers "F.Cu" "F.Mask" "F.Paste")
			(net "GND")
		)
	)
	(footprint ""
		(layer "F.Cu")
		(at 182.710836 -92.674948 -90)
		(property "Reference" "R6151"
			(at 0 0 270)
			(layer "F.SilkS")
			(hide yes)
			(effects
				(font
					(size 1.27 1.27)
				)
			)
		)
		(property "Value" ""
			(at 0 0 270)
			(layer "F.Fab")
			(effects
				(font
					(size 1.27 1.27)
				)
			)
		)
		(duplicate_pad_numbers_are_jumpers no)
		(fp_line
			(start -0.7874 0.4064)
			(end -0.7874 -0.4064)
			(stroke
				(width 0.1524)
				(type default)
			)
			(layer "F.SilkS")
		)
		(fp_line
			(start 0.7874 0.4064)
			(end -0.7874 0.4064)
			(stroke
				(width 0.1524)
				(type default)
			)
			(layer "F.SilkS")
		)
		(fp_line
			(start -0.7874 -0.4064)
			(end 0.7874 -0.4064)
			(stroke
				(width 0.1524)
				(type default)
			)
			(layer "F.SilkS")
		)
		(fp_line
			(start 0.7874 -0.4064)
			(end 0.7874 0.4064)
			(stroke
				(width 0.1524)
				(type default)
			)
			(layer "F.SilkS")
		)
		(fp_line
			(start -0.67945 0.3048)
			(end -0.67945 -0.305054)
			(stroke
				(width 0.1)
				(type default)
			)
			(layer "F.Fab")
		)
		(fp_line
			(start -0.12065 0.3048)
			(end -0.67945 0.3048)
			(stroke
				(width 0.1)
				(type default)
			)
			(layer "F.Fab")
		)
		(fp_line
			(start 0.120396 0.3048)
			(end 0.120396 0.2794)
			(stroke
				(width 0.1)
				(type default)
			)
			(layer "F.Fab")
		)
		(fp_line
			(start 0.67945 0.3048)
			(end 0.120396 0.3048)
			(stroke
				(width 0.1)
				(type default)
			)
			(layer "F.Fab")
		)
		(fp_line
			(start -0.12065 0.2794)
			(end -0.12065 0.3048)
			(stroke
				(width 0.1)
				(type default)
			)
			(layer "F.Fab")
		)
		(fp_line
			(start 0.120396 0.2794)
			(end -0.12065 0.2794)
			(stroke
				(width 0.1)
				(type default)
			)
			(layer "F.Fab")
		)
		(fp_line
			(start -0.12065 -0.2794)
			(end 0.12065 -0.2794)
			(stroke
				(width 0.1)
				(type default)
			)
			(layer "F.Fab")
		)
		(fp_line
			(start 0.12065 -0.2794)
			(end 0.12065 -0.3048)
			(stroke
				(width 0.1)
				(type default)
			)
			(layer "F.Fab")
		)
		(fp_line
			(start 0.12065 -0.3048)
			(end 0.67945 -0.3048)
			(stroke
				(width 0.1)
				(type default)
			)
			(layer "F.Fab")
		)
		(fp_line
			(start 0.67945 -0.3048)
			(end 0.67945 0.3048)
			(stroke
				(width 0.1)
				(type default)
			)
			(layer "F.Fab")
		)
		(fp_line
			(start -0.67945 -0.305054)
			(end -0.12065 -0.305054)
			(stroke
				(width 0.1)
				(type default)
			)
			(layer "F.Fab")
		)
		(fp_line
			(start -0.12065 -0.305054)
			(end -0.12065 -0.2794)
			(stroke
				(width 0.1)
				(type default)
			)
			(layer "F.Fab")
		)
		(pad "1" smd circle
			(at -0.40005 0 270)
			(size 0 0)
			(layers "F.Cu" "F.Mask" "F.Paste")
			(net "FAB_BMC_REV_ID0")
		)
		(pad "2" smd circle
			(at 0.40005 0 270)
			(size 0 0)
			(layers "F.Cu" "F.Mask" "F.Paste")
			(net "GND")
		)
	)
	(footprint ""
		(layer "F.Cu")
		(at 75.070716 -331.988668 180)
		(property "Reference" "PC202"
			(at 0 0 180)
			(layer "F.SilkS")
			(hide yes)
			(effects
				(font
					(size 1.27 1.27)
				)
			)
		)
		(property "Value" ""
			(at 0 0 180)
			(layer "F.Fab")
			(effects
				(font
					(size 1.27 1.27)
				)
			)
		)
		(duplicate_pad_numbers_are_jumpers no)
		(fp_line
			(start 0.7874 0.4064)
			(end -0.7874 0.4064)
			(stroke
				(width 0.1524)
				(type default)
			)
			(layer "F.SilkS")
		)
		(fp_line
			(start 0.7874 -0.4064)
			(end 0.7874 0.4064)
			(stroke
				(width 0.1524)
				(type default)
			)
			(layer "F.SilkS")
		)
		(fp_line
			(start -0.7874 0.4064)
			(end -0.7874 -0.4064)
			(stroke
				(width 0.1524)
				(type default)
			)
			(layer "F.SilkS")
		)
		(fp_line
			(start -0.7874 -0.4064)
			(end 0.7874 -0.4064)
			(stroke
				(width 0.1524)
				(type default)
			)
			(layer "F.SilkS")
		)
		(fp_line
			(start 0.67945 0.3048)
			(end 0.120396 0.3048)
			(stroke
				(width 0.1)
				(type default)
			)
			(layer "F.Fab")
		)
		(fp_line
			(start 0.67945 -0.3048)
			(end 0.67945 0.3048)
			(stroke
				(width 0.1)
				(type default)
			)
			(layer "F.Fab")
		)
		(fp_line
			(start 0.12065 -0.2794)
			(end 0.12065 -0.3048)
			(stroke
				(width 0.1)
				(type default)
			)
			(layer "F.Fab")
		)
		(fp_line
			(start 0.12065 -0.3048)
			(end 0.67945 -0.3048)
			(stroke
				(width 0.1)
				(type default)
			)
			(layer "F.Fab")
		)
		(fp_line
			(start 0.120396 0.3048)
			(end 0.120396 0.2794)
			(stroke
				(width 0.1)
				(type default)
			)
			(layer "F.Fab")
		)
		(fp_line
			(start 0.120396 0.2794)
			(end -0.12065 0.2794)
			(stroke
				(width 0.1)
				(type default)
			)
			(layer "F.Fab")
		)
		(fp_line
			(start -0.12065 0.3048)
			(end -0.67945 0.3048)
			(stroke
				(width 0.1)
				(type default)
			)
			(layer "F.Fab")
		)
		(fp_line
			(start -0.12065 0.2794)
			(end -0.12065 0.3048)
			(stroke
				(width 0.1)
				(type default)
			)
			(layer "F.Fab")
		)
		(fp_line
			(start -0.12065 -0.2794)
			(end 0.12065 -0.2794)
			(stroke
				(width 0.1)
				(type default)
			)
			(layer "F.Fab")
		)
		(fp_line
			(start -0.12065 -0.305054)
			(end -0.12065 -0.2794)
			(stroke
				(width 0.1)
				(type default)
			)
			(layer "F.Fab")
		)
		(fp_line
			(start -0.67945 0.3048)
			(end -0.67945 -0.305054)
			(stroke
				(width 0.1)
				(type default)
			)
			(layer "F.Fab")
		)
		(fp_line
			(start -0.67945 -0.305054)
			(end -0.12065 -0.305054)
			(stroke
				(width 0.1)
				(type default)
			)
			(layer "F.Fab")
		)
		(pad "1" smd circle
			(at -0.40005 0 180)
			(size 0 0)
			(layers "F.Cu" "F.Mask" "F.Paste")
			(net "SW_PVDDCR_CPU1_P1_SW2")
		)
		(pad "2" smd circle
			(at 0.40005 0 180)
			(size 0 0)
			(layers "F.Cu" "F.Mask" "F.Paste")
			(net "SW_PVDDCR_CPU1_P1_SW2_RC")
		)
	)
	(footprint ""
		(layer "F.Cu")
		(at 236.650022 -192.499996)
		(property "Reference" "H99"
			(at -3.30454 -6.229604 0)
			(unlocked yes)
			(layer "F.SilkS")
			(effects
				(font
					(size 0.7874 0.5842)
					(thickness 0.1524)
				)
				(justify left)
			)
		)
		(property "Value" ""
			(at 0 0 0)
			(layer "F.Fab")
			(effects
				(font
					(size 1.27 1.27)
				)
			)
		)
		(duplicate_pad_numbers_are_jumpers no)
		(pad "1" thru_hole circle
			(at 0 0)
			(size 10.0076 10.0076)
			(drill 5.6134)
			(layers "*.Cu" "*.Mask")
			(remove_unused_layers no)
			(net "GND")
			(clearance -1.9431)
		)
	)
	(footprint ""
		(layer "F.Cu")
		(at 162.251644 -375.49963 -90)
		(property "Reference" "C752"
			(at 0 0 270)
			(layer "F.SilkS")
			(hide yes)
			(effects
				(font
					(size 1.27 1.27)
				)
			)
		)
		(property "Value" ""
			(at 0 0 270)
			(layer "F.Fab")
			(effects
				(font
					(size 1.27 1.27)
				)
			)
		)
		(duplicate_pad_numbers_are_jumpers no)
		(fp_line
			(start -0.299974 0.150114)
			(end -0.299974 -0.150114)
			(stroke
				(width 0.1)
				(type default)
			)
			(layer "F.Fab")
		)
		(fp_line
			(start 0.299974 0.150114)
			(end -0.299974 0.150114)
			(stroke
				(width 0.1)
				(type default)
			)
			(layer "F.Fab")
		)
		(fp_line
			(start -0.299974 -0.150114)
			(end 0.299974 -0.150114)
			(stroke
				(width 0.1)
				(type default)
			)
			(layer "F.Fab")
		)
		(fp_line
			(start 0.299974 -0.150114)
			(end 0.299974 0.150114)
			(stroke
				(width 0.1)
				(type default)
			)
			(layer "F.Fab")
		)
		(pad "1" smd rect
			(at -0.2667 0 270)
			(size 0.3048 0.381)
			(layers "F.Cu" "F.Mask" "F.Paste")
			(net "P5E_CPU1_P2_TX_C_DN<10>")
		)
		(pad "2" smd rect
			(at 0.2667 0 270)
			(size 0.3048 0.381)
			(layers "F.Cu" "F.Mask" "F.Paste")
			(net "P5E_CPU1_P2_TX_DN<10>")
		)
	)
	(footprint ""
		(layer "F.Cu")
		(at 78.028546 -395.436852 -90)
		(property "Reference" "R793"
			(at 0 0 270)
			(layer "F.SilkS")
			(hide yes)
			(effects
				(font
					(size 1.27 1.27)
				)
			)
		)
		(property "Value" ""
			(at 0 0 270)
			(layer "F.Fab")
			(effects
				(font
					(size 1.27 1.27)
				)
			)
		)
		(duplicate_pad_numbers_are_jumpers no)
		(fp_line
			(start -0.32512 0.175006)
			(end -0.32512 -0.175006)
			(stroke
				(width 0.1)
				(type default)
			)
			(layer "F.Fab")
		)
		(fp_line
			(start 0.32512 0.175006)
			(end -0.32512 0.175006)
			(stroke
				(width 0.1)
				(type default)
			)
			(layer "F.Fab")
		)
		(fp_line
			(start -0.32512 -0.175006)
			(end 0.32512 -0.175006)
			(stroke
				(width 0.1)
				(type default)
			)
			(layer "F.Fab")
		)
		(fp_line
			(start 0.32512 -0.175006)
			(end 0.32512 0.175006)
			(stroke
				(width 0.1)
				(type default)
			)
			(layer "F.Fab")
		)
		(pad "1" smd rect
			(at -0.2667 0 270)
			(size 0.3048 0.381)
			(layers "F.Cu" "F.Mask" "F.Paste")
			(net "P1V8_CPU1_RT_1D")
		)
		(pad "2" smd rect
			(at 0.2667 0 90)
			(size 0.3048 0.381)
			(layers "F.Cu" "F.Mask" "F.Paste")
			(net "MODE_RT_CPU1_P1")
		)
	)
)
